(kicad_pcb
	(version 20260206)
	(generator "pcbnew")
	(generator_version "10.0")
	(general
		(thickness 1.6)
		(legacy_teardrops no)
	)
	(paper "A4")
	(title_block
		(title "timecard-production-celestica-r4006 — R4006-B0001-02_R01.brd")
		(comment 1 "Time Appliance Project (Time Card) / footprints 1-6 of 1113")
	)
	(layers
		(0 "F.Cu" signal "TOP")
		(4 "In1.Cu" signal "L02_GND1")
		(6 "In2.Cu" signal "L03_SIG1")
		(8 "In3.Cu" signal "L04_GND2")
		(10 "In4.Cu" signal "L05_VCC1")
		(12 "In5.Cu" signal "L06_VCC2")
		(14 "In6.Cu" signal "L07_GND3")
		(16 "In7.Cu" signal "L08_SIG2")
		(18 "In8.Cu" signal "L09_GND4")
		(2 "B.Cu" signal "BOTTOM")
		(9 "F.Adhes" user "F.Adhesive")
		(11 "B.Adhes" user "B.Adhesive")
		(13 "F.Paste" user "Package Geometry/Pastemask Top")
		(15 "B.Paste" user "Package Geometry/Pastemask Bottom")
		(5 "F.SilkS" user "Ref Des/Silkscreen Top")
		(7 "B.SilkS" user "Ref Des/Silkscreen Bottom")
		(1 "F.Mask" user "Board Geometry/Soldermask Top")
		(3 "B.Mask" user "Board Geometry/Soldermask Bottom")
		(17 "Dwgs.User" user "User.Drawings")
		(19 "Cmts.User" user "User.Comments")
		(21 "Eco1.User" user "User.Eco1")
		(23 "Eco2.User" user "User.Eco2")
		(25 "Edge.Cuts" user "Board Geometry/Outline")
		(27 "Margin" user)
		(31 "F.CrtYd" user "Package Geometry/Place Bound Top")
		(29 "B.CrtYd" user "Package Geometry/Place Bound Bottom")
		(35 "F.Fab" user "Ref Des/Assembly Top")
		(33 "B.Fab" user "Ref Des/Assembly Bottom")
	)
	(footprint ""
		(layer "F.Cu")
		(at 137.6934 -83.9724)
		(property "Reference" "CR10"
			(at -0.889 -4.65963 0)
			(unlocked yes)
			(layer "F.SilkS")
			(effects
				(font
					(size 0.7874 0.5842)
					(thickness 0.1524)
				)
			)
		)
		(property "Value" "VAL*"
			(at -0.011176 6.627876 0)
			(unlocked yes)
			(layer "F.Fab")
			(hide yes)
			(effects
				(font
					(size 0.7874 0.5842)
					(thickness 0.1524)
				)
			)
		)
		(property "Tolerance" "TOL*"
			(at 0.001524 7.60222 0)
			(unlocked yes)
			(layer "Cmts.User")
			(hide yes)
			(effects
				(font
					(size 0.7874 0.5842)
					(thickness 0.1524)
				)
			)
		)
		(property "User Part Number" "PARTNUM*"
			(at 0 5.66674 0)
			(unlocked yes)
			(layer "Cmts.User")
			(hide yes)
			(effects
				(font
					(size 0.7874 0.5842)
					(thickness 0.1524)
				)
			)
		)
		(property "Device Type" "DIODE_2E-G122-10190-01"
			(at 0 4.47294 0)
			(unlocked yes)
			(layer "F.Fab")
			(hide yes)
			(effects
				(font
					(size 0.7874 0.5842)
					(thickness 0.1524)
				)
			)
		)
		(duplicate_pad_numbers_are_jumpers no)
		(fp_line
			(start -6.311392 -1.896872)
			(end -5.041392 -1.896872)
			(stroke
				(width 0.1)
				(type default)
			)
			(layer "F.SilkS")
		)
		(fp_line
			(start -5.676392 -1.261872)
			(end -5.676392 -2.531872)
			(stroke
				(width 0.1)
				(type default)
			)
			(layer "F.SilkS")
		)
		(fp_line
			(start -4.747768 -3.363976)
			(end 4.747768 -3.363976)
			(stroke
				(width 0.1)
				(type default)
			)
			(layer "F.SilkS")
		)
		(fp_line
			(start -4.747768 3.363976)
			(end -4.747768 -3.363976)
			(stroke
				(width 0.1)
				(type default)
			)
			(layer "F.SilkS")
		)
		(fp_line
			(start 4.747768 -3.363976)
			(end 4.747768 3.363976)
			(stroke
				(width 0.1)
				(type default)
			)
			(layer "F.SilkS")
		)
		(fp_line
			(start 4.747768 3.363976)
			(end -4.747768 3.363976)
			(stroke
				(width 0.1)
				(type default)
			)
			(layer "F.SilkS")
		)
		(fp_rect
			(start -5.001768 -3.617976)
			(end 5.001768 3.617976)
			(stroke
				(width 0)
				(type default)
			)
			(fill no)
			(layer "F.CrtYd")
		)
		(fp_line
			(start -5.295392 -2.024126)
			(end -4.025392 -2.024126)
			(stroke
				(width 0.1)
				(type default)
			)
			(layer "F.Fab")
		)
		(fp_line
			(start -4.660392 -1.389126)
			(end -4.660392 -2.659126)
			(stroke
				(width 0.1)
				(type default)
			)
			(layer "F.Fab")
		)
		(fp_line
			(start -3.554984 -3.109976)
			(end 3.554984 -3.109976)
			(stroke
				(width 0.1)
				(type default)
			)
			(layer "F.Fab")
		)
		(fp_line
			(start -3.554984 3.109976)
			(end -3.554984 -3.109976)
			(stroke
				(width 0.1)
				(type default)
			)
			(layer "F.Fab")
		)
		(fp_line
			(start 3.554984 -3.109976)
			(end 3.554984 3.109976)
			(stroke
				(width 0.1)
				(type default)
			)
			(layer "F.Fab")
		)
		(fp_line
			(start 3.554984 3.109976)
			(end -3.554984 3.109976)
			(stroke
				(width 0.1)
				(type default)
			)
			(layer "F.Fab")
		)
		(fp_text user "A"
			(at -5.7404 -0.18923 0)
			(unlocked yes)
			(layer "F.SilkS")
			(effects
				(font
					(size 0.7874 0.5842)
					(thickness 0.1524)
				)
			)
		)
		(fp_text user "C"
			(at 5.9436 -0.69723 0)
			(unlocked yes)
			(layer "F.SilkS")
			(effects
				(font
					(size 0.7874 0.5842)
					(thickness 0.1524)
				)
			)
		)
		(fp_text user "A"
			(at -4.4704 0.15367 0)
			(unlocked yes)
			(layer "F.Fab")
			(effects
				(font
					(size 0.7874 0.5842)
					(thickness 0.1524)
				)
			)
		)
		(fp_text user "C"
			(at 4.1656 -0.10033 0)
			(unlocked yes)
			(layer "F.Fab")
			(effects
				(font
					(size 0.7874 0.5842)
					(thickness 0.1524)
				)
			)
		)
		(pad "A" smd rect
			(at -3.299968 0)
			(size 2.3876 3.302)
			(layers "F.Cu" "F.Mask" "F.Paste")
			(net "SG")
		)
		(pad "C" smd rect
			(at 3.299968 0)
			(size 2.3876 3.302)
			(layers "F.Cu" "F.Mask" "F.Paste")
			(net "XP12R0V_IN")
		)
	)
	(footprint ""
		(layer "F.Cu")
		(at 146.558 -15.4686)
		(property "Reference" "C231"
			(at 2.667 1.02997 0)
			(unlocked yes)
			(layer "F.SilkS")
			(effects
				(font
					(size 0.7874 0.5842)
					(thickness 0.1524)
				)
			)
		)
		(property "Value" "VAL*"
			(at 0.193548 2.13614 0)
			(unlocked yes)
			(layer "F.Fab")
			(hide yes)
			(effects
				(font
					(size 0.7874 0.5842)
					(thickness 0.1524)
				)
			)
		)
		(property "Tolerance" "TOL*"
			(at 0.216154 3.1496 0)
			(unlocked yes)
			(layer "Cmts.User")
			(hide yes)
			(effects
				(font
					(size 0.7874 0.5842)
					(thickness 0.1524)
				)
			)
		)
		(property "Device Type" "CAPACITOR-G104-0B103-EK,0.01UFA"
			(at 0.184404 1.180592 0)
			(unlocked yes)
			(layer "F.Fab")
			(hide yes)
			(effects
				(font
					(size 0.7874 0.5842)
					(thickness 0.1524)
				)
			)
		)
		(property "User Part Number" "PARTNUM*"
			(at 0.216154 4.185666 0)
			(unlocked yes)
			(layer "Cmts.User")
			(hide yes)
			(effects
				(font
					(size 0.7874 0.5842)
					(thickness 0.1524)
				)
			)
		)
		(duplicate_pad_numbers_are_jumpers no)
		(fp_line
			(start -0.671322 -0.4445)
			(end 0.671322 -0.4445)
			(stroke
				(width 0.1)
				(type default)
			)
			(layer "F.SilkS")
		)
		(fp_line
			(start -0.671322 0.4445)
			(end -0.671322 -0.4445)
			(stroke
				(width 0.1)
				(type default)
			)
			(layer "F.SilkS")
		)
		(fp_line
			(start 0.671322 -0.4445)
			(end 0.671322 0.4445)
			(stroke
				(width 0.1)
				(type default)
			)
			(layer "F.SilkS")
		)
		(fp_line
			(start 0.671322 0.4445)
			(end -0.671322 0.4445)
			(stroke
				(width 0.1)
				(type default)
			)
			(layer "F.SilkS")
		)
		(fp_rect
			(start 0.671322 -0.4445)
			(end -0.671322 0.4445)
			(stroke
				(width 0)
				(type default)
			)
			(fill no)
			(layer "F.CrtYd")
		)
		(fp_line
			(start -0.31496 -0.1651)
			(end -0.31496 0.1651)
			(stroke
				(width 0.1)
				(type default)
			)
			(layer "F.Fab")
		)
		(fp_line
			(start -0.31496 0.1651)
			(end 0.31496 0.1651)
			(stroke
				(width 0.1)
				(type default)
			)
			(layer "F.Fab")
		)
		(fp_line
			(start 0.31496 -0.1651)
			(end -0.31496 -0.1651)
			(stroke
				(width 0.1)
				(type default)
			)
			(layer "F.Fab")
		)
		(fp_line
			(start 0.31496 0.1651)
			(end 0.31496 -0.1651)
			(stroke
				(width 0.1)
				(type default)
			)
			(layer "F.Fab")
		)
		(pad "1" smd rect
			(at -0.264922 0)
			(size 0.3048 0.381)
			(layers "F.Cu" "F.Mask" "F.Paste")
			(net "UNNAMED_515_CAPACITOR_I132_1")
		)
		(pad "2" smd rect
			(at 0.264922 0)
			(size 0.3048 0.381)
			(layers "F.Cu" "F.Mask" "F.Paste")
			(net "SG")
		)
		(zone
			(layer "F.Cu")
			(hatch none 0.5)
			(connect_pads
				(clearance 0)
			)
			(min_thickness 0.25)
			(keepout
				(tracks allowed)
				(vias not_allowed)
				(pads allowed)
				(copperpour not_allowed)
				(footprints allowed)
			)
			(placement
				(enabled no)
				(sheetname "")
			)
			(fill
				(thermal_gap 0.5)
				(thermal_bridge_width 0.5)
				(island_removal_mode 0)
			)
			(polygon
				(pts
					(xy 146.670522 -15.6591) (xy 146.445478 -15.6591) (xy 146.445478 -15.2781) (xy 146.670522 -15.2781)
				)
			)
		)
	)
	(footprint ""
		(layer "F.Cu")
		(at 112.7506 -24.7142)
		(property "Reference" "R241"
			(at -0.2286 8.62457 0)
			(unlocked yes)
			(layer "F.SilkS")
			(effects
				(font
					(size 0.7874 0.5842)
					(thickness 0.1524)
				)
			)
		)
		(property "Value" "VAL*"
			(at 0.02032 2.13233 0)
			(unlocked yes)
			(layer "F.Fab")
			(hide yes)
			(effects
				(font
					(size 0.7874 0.5842)
					(thickness 0.1524)
				)
			)
		)
		(property "Device Type" "RESISTOR-G155-11500-01,150OHM,A"
			(at 0.008382 1.210564 0)
			(unlocked yes)
			(layer "F.Fab")
			(hide yes)
			(effects
				(font
					(size 0.7874 0.5842)
					(thickness 0.1524)
				)
			)
		)
		(property "User Part Number" "PARTNUM*"
			(at 0.02032 4.024884 0)
			(unlocked yes)
			(layer "Cmts.User")
			(hide yes)
			(effects
				(font
					(size 0.7874 0.5842)
					(thickness 0.1524)
				)
			)
		)
		(property "Tolerance" "TOL*"
			(at 0.044704 3.05435 0)
			(unlocked yes)
			(layer "Cmts.User")
			(hide yes)
			(effects
				(font
					(size 0.7874 0.5842)
					(thickness 0.1524)
				)
			)
		)
		(duplicate_pad_numbers_are_jumpers no)
		(fp_line
			(start -1.143 -0.5588)
			(end -1.143 0.5588)
			(stroke
				(width 0.1)
				(type default)
			)
			(layer "F.SilkS")
		)
		(fp_line
			(start -1.143 0.5588)
			(end 1.143 0.5588)
			(stroke
				(width 0.1)
				(type default)
			)
			(layer "F.SilkS")
		)
		(fp_line
			(start 1.143 -0.5588)
			(end -1.143 -0.5588)
			(stroke
				(width 0.1)
				(type default)
			)
			(layer "F.SilkS")
		)
		(fp_line
			(start 1.143 0.5588)
			(end 1.143 -0.5588)
			(stroke
				(width 0.1)
				(type default)
			)
			(layer "F.SilkS")
		)
		(fp_rect
			(start -1.143 -0.5588)
			(end 1.143 0.5588)
			(stroke
				(width 0)
				(type default)
			)
			(fill no)
			(layer "F.CrtYd")
		)
		(fp_line
			(start -0.508 -0.3048)
			(end -0.508 0.3048)
			(stroke
				(width 0.1)
				(type default)
			)
			(layer "F.Fab")
		)
		(fp_line
			(start -0.508 0.3048)
			(end 0.508 0.3048)
			(stroke
				(width 0.1)
				(type default)
			)
			(layer "F.Fab")
		)
		(fp_line
			(start 0.508 -0.3048)
			(end -0.508 -0.3048)
			(stroke
				(width 0.1)
				(type default)
			)
			(layer "F.Fab")
		)
		(fp_line
			(start 0.508 0.3048)
			(end 0.508 -0.3048)
			(stroke
				(width 0.1)
				(type default)
			)
			(layer "F.Fab")
		)
		(pad "1" smd rect
			(at -0.5334 0)
			(size 0.7112 0.6096)
			(layers "F.Cu" "F.Mask" "F.Paste")
			(net "OSC_200M_CLKP")
		)
		(pad "2" smd rect
			(at 0.5334 0)
			(size 0.7112 0.6096)
			(layers "F.Cu" "F.Mask" "F.Paste")
			(net "SG")
		)
		(zone
			(layer "F.Cu")
			(hatch none 0.5)
			(connect_pads
				(clearance 0)
			)
			(min_thickness 0.25)
			(keepout
				(tracks allowed)
				(vias not_allowed)
				(pads allowed)
				(copperpour not_allowed)
				(footprints allowed)
			)
			(placement
				(enabled no)
				(sheetname "")
			)
			(fill
				(thermal_gap 0.5)
				(thermal_bridge_width 0.5)
				(island_removal_mode 0)
			)
			(polygon
				(pts
					(xy 112.6744 -25.019) (xy 112.6744 -24.4094) (xy 112.8268 -24.4094) (xy 112.8268 -25.019)
				)
			)
		)
	)
	(footprint ""
		(layer "F.Cu")
		(at 124.714 -39.116)
		(property "Reference" "TP137"
			(at -0.60325 0.9398 90)
			(unlocked yes)
			(layer "F.SilkS")
			(effects
				(font
					(size 0.635 0.4064)
					(thickness 0.1524)
				)
				(justify left)
			)
		)
		(property "Value" ""
			(at 0 0 0)
			(layer "F.Fab")
			(effects
				(font
					(size 1.27 1.27)
				)
			)
		)
		(property "Device Type" "TP_PIONT-TP010CT020B030_PTH-TPA"
			(at -1.341882 0.996696 0)
			(unlocked yes)
			(layer "F.Fab")
			(hide yes)
			(effects
				(font
					(size 0.7874 0.5842)
					(thickness 0.1524)
				)
				(justify left)
			)
		)
		(duplicate_pad_numbers_are_jumpers no)
		(fp_poly
			(pts
				(arc
					(start 0.889 0)
					(mid -0.889 0)
					(end 0.889 0)
				)
			)
			(stroke
				(width 0)
				(type default)
			)
			(fill no)
			(layer "B.CrtYd")
		)
		(fp_poly
			(pts
				(arc
					(start 0.889 0)
					(mid -0.889 0)
					(end 0.889 0)
				)
			)
			(stroke
				(width 0)
				(type default)
			)
			(fill no)
			(layer "F.CrtYd")
		)
		(pad "1" thru_hole circle
			(at 0 0)
			(size 0.508 0.508)
			(drill 0.254)
			(layers "*.Cu" "*.Mask")
			(remove_unused_layers no)
			(net "IO_L22N_34")
			(clearance 0.1016)
			(padstack
				(mode front_inner_back)
				(layer "Inner"
					(shape circle)
					(size 0.508 0.508)
					(clearance 0.1016)
				)
				(layer "B.Cu"
					(shape circle)
					(size 0.762 0.762)
					(clearance -0.0254)
				)
			)
		)
	)
	(footprint ""
		(layer "F.Cu")
		(at 145.8214 -90.6018)
		(property "Reference" "C3"
			(at -0.2794 8.21817 0)
			(unlocked yes)
			(layer "F.SilkS")
			(effects
				(font
					(size 0.7874 0.5842)
					(thickness 0.1524)
				)
			)
		)
		(property "Value" "VAL*"
			(at 0.0762 2.067306 0)
			(unlocked yes)
			(layer "F.Fab")
			(hide yes)
			(effects
				(font
					(size 0.7874 0.5842)
					(thickness 0.1524)
				)
			)
		)
		(property "Device Type" "CAPACITOR-G105-0B104-EK,0.1UF,A"
			(at 0.0508 1.127506 0)
			(unlocked yes)
			(layer "F.Fab")
			(hide yes)
			(effects
				(font
					(size 0.7874 0.5842)
					(thickness 0.1524)
				)
			)
		)
		(property "User Part Number" "PARTNUM*"
			(at 0.1016 4.023106 0)
			(unlocked yes)
			(layer "Cmts.User")
			(hide yes)
			(effects
				(font
					(size 0.7874 0.5842)
					(thickness 0.1524)
				)
			)
		)
		(property "Tolerance" "TOL*"
			(at 0.0762 3.032506 0)
			(unlocked yes)
			(layer "Cmts.User")
			(hide yes)
			(effects
				(font
					(size 0.7874 0.5842)
					(thickness 0.1524)
				)
			)
		)
		(duplicate_pad_numbers_are_jumpers no)
		(fp_line
			(start -1.143 -0.5588)
			(end -1.143 0.5588)
			(stroke
				(width 0.1)
				(type default)
			)
			(layer "F.SilkS")
		)
		(fp_line
			(start -1.143 0.5588)
			(end 1.143 0.5588)
			(stroke
				(width 0.1)
				(type default)
			)
			(layer "F.SilkS")
		)
		(fp_line
			(start 1.143 -0.5588)
			(end -1.143 -0.5588)
			(stroke
				(width 0.1)
				(type default)
			)
			(layer "F.SilkS")
		)
		(fp_line
			(start 1.143 0.5588)
			(end 1.143 -0.5588)
			(stroke
				(width 0.1)
				(type default)
			)
			(layer "F.SilkS")
		)
		(fp_rect
			(start -1.143 -0.5588)
			(end 1.143 0.5588)
			(stroke
				(width 0)
				(type default)
			)
			(fill no)
			(layer "F.CrtYd")
		)
		(fp_line
			(start -0.508 -0.3048)
			(end -0.508 0.3048)
			(stroke
				(width 0.1)
				(type default)
			)
			(layer "F.Fab")
		)
		(fp_line
			(start -0.508 0.3048)
			(end 0.508 0.3048)
			(stroke
				(width 0.1)
				(type default)
			)
			(layer "F.Fab")
		)
		(fp_line
			(start 0.508 -0.3048)
			(end -0.508 -0.3048)
			(stroke
				(width 0.1)
				(type default)
			)
			(layer "F.Fab")
		)
		(fp_line
			(start 0.508 0.3048)
			(end 0.508 -0.3048)
			(stroke
				(width 0.1)
				(type default)
			)
			(layer "F.Fab")
		)
		(pad "1" smd rect
			(at -0.5334 0)
			(size 0.7112 0.6096)
			(layers "F.Cu" "F.Mask" "F.Paste")
			(net "XP12R0V_A_EN")
		)
		(pad "2" smd rect
			(at 0.5334 0)
			(size 0.7112 0.6096)
			(layers "F.Cu" "F.Mask" "F.Paste")
			(net "SG")
		)
		(zone
			(layer "F.Cu")
			(hatch none 0.5)
			(connect_pads
				(clearance 0)
			)
			(min_thickness 0.25)
			(keepout
				(tracks allowed)
				(vias not_allowed)
				(pads allowed)
				(copperpour not_allowed)
				(footprints allowed)
			)
			(placement
				(enabled no)
				(sheetname "")
			)
			(fill
				(thermal_gap 0.5)
				(thermal_bridge_width 0.5)
				(island_removal_mode 0)
			)
			(polygon
				(pts
					(xy 145.7452 -90.9066) (xy 145.7452 -90.297) (xy 145.8976 -90.297) (xy 145.8976 -90.9066)
				)
			)
		)
	)
	(footprint ""
		(layer "F.Cu")
		(at 112.7125 -28.5242)
		(property "Reference" "R359"
			(at 2.00787 2.1082 90)
			(unlocked yes)
			(layer "F.SilkS")
			(effects
				(font
					(size 0.7874 0.5842)
					(thickness 0.1524)
				)
			)
		)
		(property "Value" "VAL*"
			(at 0.02032 2.13233 0)
			(unlocked yes)
			(layer "F.Fab")
			(hide yes)
			(effects
				(font
					(size 0.7874 0.5842)
					(thickness 0.1524)
				)
			)
		)
		(property "Tolerance" "TOL*"
			(at 0.044704 3.05435 0)
			(unlocked yes)
			(layer "Cmts.User")
			(hide yes)
			(effects
				(font
					(size 0.7874 0.5842)
					(thickness 0.1524)
				)
			)
		)
		(property "User Part Number" "PARTNUM*"
			(at 0.02032 4.024884 0)
			(unlocked yes)
			(layer "Cmts.User")
			(hide yes)
			(effects
				(font
					(size 0.7874 0.5842)
					(thickness 0.1524)
				)
			)
		)
		(property "Device Type" "RESISTOR-G155-11002-01,10KOHM,A"
			(at 0.008382 1.210564 0)
			(unlocked yes)
			(layer "F.Fab")
			(hide yes)
			(effects
				(font
					(size 0.7874 0.5842)
					(thickness 0.1524)
				)
			)
		)
		(duplicate_pad_numbers_are_jumpers no)
		(fp_line
			(start -1.143 -0.5588)
			(end -1.143 0.5588)
			(stroke
				(width 0.1)
				(type default)
			)
			(layer "F.SilkS")
		)
		(fp_line
			(start -1.143 0.5588)
			(end 1.143 0.5588)
			(stroke
				(width 0.1)
				(type default)
			)
			(layer "F.SilkS")
		)
		(fp_line
			(start 1.143 -0.5588)
			(end -1.143 -0.5588)
			(stroke
				(width 0.1)
				(type default)
			)
			(layer "F.SilkS")
		)
		(fp_line
			(start 1.143 0.5588)
			(end 1.143 -0.5588)
			(stroke
				(width 0.1)
				(type default)
			)
			(layer "F.SilkS")
		)
		(fp_poly
			(pts
				(xy -1.143 0.5588) (xy 1.143 0.5588) (xy 1.143 -0.5588) (xy -1.143 -0.5588)
			)
			(stroke
				(width 0)
				(type default)
			)
			(fill no)
			(layer "F.CrtYd")
		)
		(fp_line
			(start -0.508 -0.3048)
			(end -0.508 0.3048)
			(stroke
				(width 0.1)
				(type default)
			)
			(layer "F.Fab")
		)
		(fp_line
			(start -0.508 0.3048)
			(end 0.508 0.3048)
			(stroke
				(width 0.1)
				(type default)
			)
			(layer "F.Fab")
		)
		(fp_line
			(start 0.508 -0.3048)
			(end -0.508 -0.3048)
			(stroke
				(width 0.1)
				(type default)
			)
			(layer "F.Fab")
		)
		(fp_line
			(start 0.508 0.3048)
			(end 0.508 -0.3048)
			(stroke
				(width 0.1)
				(type default)
			)
			(layer "F.Fab")
		)
		(pad "1" smd rect
			(at -0.5334 0)
			(size 0.7112 0.6096)
			(layers "F.Cu" "F.Mask" "F.Paste")
			(net "MHZ200CLKP_CLKIN")
		)
		(pad "2" smd rect
			(at 0.5334 0)
			(size 0.7112 0.6096)
			(layers "F.Cu" "F.Mask" "F.Paste")
			(net "SG")
		)
		(zone
			(layer "F.Cu")
			(hatch none 0.5)
			(connect_pads
				(clearance 0)
			)
			(min_thickness 0.25)
			(keepout
				(tracks allowed)
				(vias not_allowed)
				(pads allowed)
				(copperpour not_allowed)
				(footprints allowed)
			)
			(placement
				(enabled no)
				(sheetname "")
			)
			(fill
				(thermal_gap 0.5)
				(thermal_bridge_width 0.5)
				(island_removal_mode 0)
			)
			(polygon
				(pts
					(xy 112.6363 -28.2194) (xy 112.7887 -28.2194) (xy 112.7887 -28.829) (xy 112.6363 -28.829)
				)
			)
		)
		(zone
			(layer "F.Cu")
			(hatch none 0.5)
			(connect_pads
				(clearance 0)
			)
			(min_thickness 0.25)
			(keepout
				(tracks not_allowed)
				(vias allowed)
				(pads allowed)
				(copperpour not_allowed)
				(footprints allowed)
			)
			(placement
				(enabled no)
				(sheetname "")
			)
			(fill
				(thermal_gap 0.5)
				(thermal_bridge_width 0.5)
				(island_removal_mode 0)
			)
			(polygon
				(pts
					(xy 112.6363 -28.2194) (xy 112.7887 -28.2194) (xy 112.7887 -28.829) (xy 112.6363 -28.829)
				)
			)
		)
	)
)
